# S9S_MB_2U (Grand Teton) — schematic netlist excerpt (pin names and nets, part order shuffled) for the footprints in the layout excerpt that follows; sources: Cadence DE-HDL packaged netlist, KiCad conversion of 03242023_DA0F0TMBIJ0_F0T_Motherboard_J_brd_V01_OCP.brd

J2  SCONN288_ADR50017P087CC  SCONN288_ADR50017-P087CC IO  pkg DDR288S_1-1VXB  page 83
  VIN_BULK0  = P12V_S3_AUX_CPU0_NVDIMM
  RFU0  = TP_CHA_CPU0_DIMM2_FRU_0
  VIN_MGMT  = P3V3_AUX
  HSCL  = I3C_SPD_DDRABCD_CPU0_LVC1_SCL_1
  HSDA  = I3C_SPD_DDRABCD_CPU0_LVC1_SDA
  VSS0  = GND
  DQ0_A  = M_A_CPU0_SA_DQ<0>
  VSS1  = GND
  DQ1_A  = M_A_CPU0_SA_DQ<1>
  VSS2  = GND
  DQS0_A_T  = M_A_CPU0_SA_DQS_DP<0>
  DQS0_A_C  = M_A_CPU0_SA_DQS_DN<0>
  VSS3  = GND
  DQ4_A  = M_A_CPU0_SA_DQ<4>
  VSS4  = GND
  DQ5_A  = M_A_CPU0_SA_DQ<5>
  VSS5  = GND
  DQ8_A  = M_A_CPU0_SA_DQ<8>
  VSS6  = GND
  DQ9_A  = M_A_CPU0_SA_DQ<9>
  VSS7  = GND
  DQS1_A_T  = M_A_CPU0_SA_DQS_DP<1>
  DQS1_A_C  = M_A_CPU0_SA_DQS_DN<1>
  VSS8  = GND
  DQ12_A  = M_A_CPU0_SA_DQ<12>
  VSS9  = GND
  DQ13_A  = M_A_CPU0_SA_DQ<13>
  VSS10  = GND
  DQ16_A  = M_A_CPU0_SA_DQ<16>
  VSS11  = GND
  DQ17_A  = M_A_CPU0_SA_DQ<17>
  VSS12  = GND
  DQS2_A_T  = M_A_CPU0_SA_DQS_DP<2>
  DQS2_A_C  = M_A_CPU0_SA_DQS_DN<2>
  VSS13  = GND
  DQ20_A  = M_A_CPU0_SA_DQ<20>
  VSS14  = GND
  DQ21_A  = M_A_CPU0_SA_DQ<21>
  VSS15  = GND
  DQ24_A  = M_A_CPU0_SA_DQ<24>
  VSS16  = GND
  DQ25_A  = M_A_CPU0_SA_DQ<25>
  VSS17  = GND
  DQS3_A_T  = M_A_CPU0_SA_DQS_DP<3>
  DQS3_A_C  = M_A_CPU0_SA_DQS_DN<3>
  VSS18  = GND
  DQ28_A  = M_A_CPU0_SA_DQ<28>
  VSS19  = GND
  DQ29_A  = M_A_CPU0_SA_DQ<29>
  VSS20  = GND
  CB0_A  = M_A_CPU0_SA_CB<0>
  VSS21  = GND
  CB1_A  = M_A_CPU0_SA_CB<1>
  VSS22  = GND
  DQS4_A_T  = M_A_CPU0_SA_DQS_DP<4>
  DQS4_A_C  = M_A_CPU0_SA_DQS_DN<4>
  VSS23  = GND
  CB4_A  = M_A_CPU0_SA_CB<4>
  VSS24  = GND
  CB5_A  = M_A_CPU0_SA_CB<5>
  VSS25  = GND
  ALERT_N  = M_A_CPU0_ALERT_N
  VSS26  = GND
  CS0_A_N  = M_A_CPU0_SA_CS_N<2>
  VSS27  = GND
  CA0_A  = M_A_CPU0_SA_CA<0>
  VSS28  = GND
  CA2_A  = M_A_CPU0_SA_CA<2>
  VSS29  = GND
  CA4_A  = M_A_CPU0_SA_CA<4>
  VSS30  = GND
  CA6_A  = M_A_CPU0_SA_CA<6>
  VSS31  = GND
  PAR_A  = M_A_CPU0_SA_PAR
  VSS32  = GND
  CA0_B  = M_A_CPU0_SB_CA<0>
  VSS33  = GND
  CA2_B  = M_A_CPU0_SB_CA<2>
  VSS34  = GND
  CA4_B  = M_A_CPU0_SB_CA<4>
  VSS35  = GND
  CA6_B  = M_A_CPU0_SB_CA<6>
  VSS36  = GND
  CS0_B_N  = M_A_CPU0_SB_CS_N<2>
  VSS37  = GND
  \lbd||rsp_a_n\  = M_A_CPU0_SA_RSP<1>
  \lbs||rsp_b_n\  = M_A_CPU0_SB_RSP<1>
  VSS38  = GND
  CB4_B  = M_A_CPU0_SB_CB<4>
  VSS39  = GND
  CB5_B  = M_A_CPU0_SB_CB<5>
  VSS40  = GND
  \dqs9_b_t||tdqs9_b_t||dbi4_b_n\  = M_A_CPU0_SB_DQS_DP<9>
  \dqs9_b_c||tdqs9_b_c\  = M_A_CPU0_SB_DQS_DN<9>
  VSS41  = GND
  CB0_B  = M_A_CPU0_SB_CB<0>
  VSS42  = GND
  CB1_B  = M_A_CPU0_SB_CB<1>
  VSS43  = GND
  DQ0_B  = M_A_CPU0_SB_DQ<0>
  VSS44  = GND
  DQ1_B  = M_A_CPU0_SB_DQ<1>
  VSS45  = GND
  DQS0_B_T  = M_A_CPU0_SB_DQS_DP<0>
  DQS0_B_C  = M_A_CPU0_SB_DQS_DN<0>
  VSS46  = GND
  DQ4_B  = M_A_CPU0_SB_DQ<4>
  VSS47  = GND
  DQ5_B  = M_A_CPU0_SB_DQ<5>
  VSS48  = GND
  DQ8_B  = M_A_CPU0_SB_DQ<8>
  VSS49  = GND
  DQ9_B  = M_A_CPU0_SB_DQ<9>
  VSS50  = GND
  DQS1_B_T  = M_A_CPU0_SB_DQS_DP<1>
  DQS1_B_C  = M_A_CPU0_SB_DQS_DN<1>
  VSS51  = GND
  DQ12_B  = M_A_CPU0_SB_DQ<12>
  VSS52  = GND
  DQ13_B  = M_A_CPU0_SB_DQ<13>
  VSS53  = GND
  DQ16_B  = M_A_CPU0_SB_DQ<16>
  VSS54  = GND
  DQ17_B  = M_A_CPU0_SB_DQ<17>
  VSS55  = GND
  DQS2_B_T  = M_A_CPU0_SB_DQS_DP<2>
  DQS2_B_C  = M_A_CPU0_SB_DQS_DN<2>
  VSS56  = GND
  DQ20_B  = M_A_CPU0_SB_DQ<20>
  VSS57  = GND
  DQ21_B  = M_A_CPU0_SB_DQ<21>
  VSS58  = GND
  DQ24_B  = M_A_CPU0_SB_DQ<24>
  VSS59  = GND
  DQ25_B  = M_A_CPU0_SB_DQ<25>
  VSS60  = GND
  DQS3_B_T  = M_A_CPU0_SB_DQS_DP<3>
  DQS3_B_C  = M_A_CPU0_SB_DQS_DN<3>
  VSS61  = GND
  DQ28_B  = M_A_CPU0_SB_DQ<28>
  VSS62  = GND
  DQ29_B  = M_A_CPU0_SB_DQ<29>
  VSS63  = GND
  RFU1  = TP_CHA_CPU0_DIMM2_FRU_1
  VIN_BULK1  = P12V_S3_AUX_CPU0_NVDIMM
  VIN_BULK2  = P12V_S3_AUX_CPU0_NVDIMM
  \pwr_good||fail_n\  = PWRGD_CHA_CPU0_DIMM2
  HSA  = PD_CHA_CPU0_DIMM2_SAA
  RFU2  = TP_CHA_CPU0_DIMM2_FRU_2
  RFU3  = TP_CHA_CPU0_DIMM2_FRU_3
  VSS64  = GND
  DQ2_A  = M_A_CPU0_SA_DQ<2>
  VSS65  = GND
  DQ3_A  = M_A_CPU0_SA_DQ<3>
  VSS66  = GND
  \dqs5_a_c||tdqs5_a_c||dqs5_a_t||tdqs5_a_t\  = M_A_CPU0_SA_DQS_DN<5>
  \dqs5_a_t||tdqs5_a_t\  = M_A_CPU0_SA_DQS_DP<5>
  VSS67  = GND
  DQ6_A  = M_A_CPU0_SA_DQ<6>
  VSS68  = GND
  DQ7_A  = M_A_CPU0_SA_DQ<7>
  VSS69  = GND
  DQ10_A  = M_A_CPU0_SA_DQ<10>
  VSS70  = GND
  DQ11_A  = M_A_CPU0_SA_DQ<11>
  VSS71  = GND
  \dqs6_a_c||tdqs6_a_c||dqs6_a_t||tdqs6_a_t\  = M_A_CPU0_SA_DQS_DN<6>
  \dqs6_a_t||tdqs6_a_t\  = M_A_CPU0_SA_DQS_DP<6>
  VSS72  = GND
  DQ14_A  = M_A_CPU0_SA_DQ<14>
  VSS73  = GND
  DQ15_A  = M_A_CPU0_SA_DQ<15>
  VSS74  = GND
  DQ18_A  = M_A_CPU0_SA_DQ<18>
  VSS75  = GND
  DQ19_A  = M_A_CPU0_SA_DQ<19>
  VSS76  = GND
  \dqs7_a_c||tdqs7_a_c\  = M_A_CPU0_SA_DQS_DN<7>
  \dqs7_a_t||tdqs7_a_t\  = M_A_CPU0_SA_DQS_DP<7>
  VSS77  = GND
  DQ22_A  = M_A_CPU0_SA_DQ<22>
  VSS78  = GND
  DQ23_A  = M_A_CPU0_SA_DQ<23>
  VSS79  = GND
  DQ26_A  = M_A_CPU0_SA_DQ<26>
  VSS80  = GND
  DQ27_A  = M_A_CPU0_SA_DQ<27>
  VSS81  = GND
  \dqs8_a_c||tdqs8_a_c\  = M_A_CPU0_SA_DQS_DN<8>
  \dqs8_a_t||tdqs8_a_t\  = M_A_CPU0_SA_DQS_DP<8>
  VSS82  = GND
  DQ30_A  = M_A_CPU0_SA_DQ<30>
  VSS83  = GND
  DQ31_A  = M_A_CPU0_SA_DQ<31>
  VSS84  = GND
  CB2_A  = M_A_CPU0_SA_CB<2>
  VSS85  = GND
  CB3_A  = M_A_CPU0_SA_CB<3>
  VSS86  = GND
  \dqs9_a_c||tdqs9_a_c\  = M_A_CPU0_SA_DQS_DN<9>
  \dqs9_a_t||tdqs9_a_t\  = M_A_CPU0_SA_DQS_DP<9>
  VSS87  = GND
  CB6_A  = M_A_CPU0_SA_CB<6>
  VSS88  = GND
  CB7_A  = M_A_CPU0_SA_CB<7>
  VSS89  = GND
  RESET_N  = RST_M_AB_CPU0_FPGA_N
  VSS90  = GND
  CS1_A_N  = M_A_CPU0_SA_CS_N<3>
  VSS91  = GND
  CA1_A  = M_A_CPU0_SA_CA<1>
  VSS92  = GND
  CA3_A  = M_A_CPU0_SA_CA<3>
  VSS93  = GND
  CA5_A  = M_A_CPU0_SA_CA<5>
  VSS94  = GND
  CK_T  = M_A_CPU0_CLK_DP<1>
  CK_C  = M_A_CPU0_CLK_DN<1>
  VSS95  = GND
  RFU4  = TP_CHA_CPU0_DIMM2_FRU_4
  CA1_B  = M_A_CPU0_SB_CA<1>
  VSS96  = GND
  CA3_B  = M_A_CPU0_SB_CA<3>
  VSS97  = GND
  CA5_B  = M_A_CPU0_SB_CA<5>
  VSS98  = GND
  PAR_B  = M_A_CPU0_SB_PAR
  VSS99  = GND
  CS1_B_N  = M_A_CPU0_SB_CS_N<3>
  VSS100  = GND
  RFU5  = TP_CHA_CPU0_DIMM2_FRU_5
  RFU6  = TP_CHA_CPU0_DIMM2_FRU_6
  VSS101  = GND
  CB6_B  = M_A_CPU0_SB_CB<6>
  VSS102  = GND
  CB7_B  = M_A_CPU0_SB_CB<7>
  VSS103  = GND
  DQS4_B_C  = M_A_CPU0_SB_DQS_DN<4>
  DQS4_B_T  = M_A_CPU0_SB_DQS_DP<4>
  VSS104  = GND
  CB2_B  = M_A_CPU0_SB_CB<2>
  VSS105  = GND
  CB3_B  = M_A_CPU0_SB_CB<3>
  VSS106  = GND
  DQ2_B  = M_A_CPU0_SB_DQ<2>
  VSS107  = GND
  DQ3_B  = M_A_CPU0_SB_DQ<3>
  VSS108  = GND
  \dqs5_b_c||tdqs5_b_c\  = M_A_CPU0_SB_DQS_DN<5>
  \dqs5_b_t||tdqs5_b_t\  = M_A_CPU0_SB_DQS_DP<5>
  VSS109  = GND
  DQ6_B  = M_A_CPU0_SB_DQ<6>
  VSS110  = GND
  DQ7_B  = M_A_CPU0_SB_DQ<7>
  VSS111  = GND
  DQ10_B  = M_A_CPU0_SB_DQ<10>
  VSS112  = GND
  DQ11_B  = M_A_CPU0_SB_DQ<11>
  VSS113  = GND
  \dqs6_b_c||tdqs6_b_c\  = M_A_CPU0_SB_DQS_DN<6>
  \dqs6_b_t||tdqs6_b_t\  = M_A_CPU0_SB_DQS_DP<6>
  VSS114  = GND
  DQ14_B  = M_A_CPU0_SB_DQ<14>
  VSS115  = GND
  DQ15_B  = M_A_CPU0_SB_DQ<15>
  VSS116  = GND
  DQ18_B  = M_A_CPU0_SB_DQ<18>
  VSS117  = GND
  DQ19_B  = M_A_CPU0_SB_DQ<19>
  VSS118  = GND
  \dqs7_b_c||tdqs7_b_c\  = M_A_CPU0_SB_DQS_DN<7>
  \dqs7_b_t||tdqs7_b_t\  = M_A_CPU0_SB_DQS_DP<7>
  VSS119  = GND
  DQ22_B  = M_A_CPU0_SB_DQ<22>
  VSS120  = GND
  DQ23_B  = M_A_CPU0_SB_DQ<23>
  VSS121  = GND
  DQ26_B  = M_A_CPU0_SB_DQ<26>
  VSS122  = GND
  DQ27_B  = M_A_CPU0_SB_DQ<27>
  VSS123  = GND
  \dqs8_b_c||tdqs8_b_c\  = M_A_CPU0_SB_DQS_DN<8>
  \dqs8_b_t||tdqs8_b_t\  = M_A_CPU0_SB_DQS_DP<8>
  VSS124  = GND
  DQ30_B  = M_A_CPU0_SB_DQ<30>
  VSS125  = GND
  DQ31_B  = M_A_CPU0_SB_DQ<31>
  VSS126  = GND
  G1  = GND
  G2  = GND
  G3  = GND

(kicad_pcb
	(version 20260206)
	(generator "pcbnew")
	(generator_version "10.0")
	(general
		(thickness 1.6)
		(legacy_teardrops no)
	)
	(paper "A4")
	(title_block
		(title "03242023_DA0F0TMBIJ0_F0T_Motherboard_J_brd_V01_OCP.brd")
		(comment 1 "Grand Teton / footprint 2856 of 6105 (J2), pads 183-228 of 291")
	)
	(layers
		(0 "F.Cu" signal "TOP")
		(4 "In1.Cu" signal "GND")
		(6 "In2.Cu" signal "IN1")
		(8 "In3.Cu" signal "GND1")
		(10 "In4.Cu" signal "IN2")
		(12 "In5.Cu" signal "GND2")
		(14 "In6.Cu" signal "IN3")
		(16 "In7.Cu" signal "GND3")
		(18 "In8.Cu" signal "VCC")
		(20 "In9.Cu" signal "VCC1")
		(22 "In10.Cu" signal "GND4")
		(24 "In11.Cu" signal "IN4")
		(26 "In12.Cu" signal "GND5")
		(28 "In13.Cu" signal "IN5")
		(30 "In14.Cu" signal "GND6")
		(32 "In15.Cu" signal "IN6")
		(34 "In16.Cu" signal "GND7")
		(2 "B.Cu" signal "BOTTOM")
		(9 "F.Adhes" user "F.Adhesive")
		(11 "B.Adhes" user "B.Adhesive")
		(13 "F.Paste" user "Package Geometry/Pastemask Top")
		(15 "B.Paste" user "Package Geometry/Pastemask Bottom")
		(5 "F.SilkS" user "Ref Des/Silkscreen Top")
		(7 "B.SilkS" user "Ref Des/Silkscreen Bottom")
		(1 "F.Mask" user "Board Geometry/Soldermask Top")
		(3 "B.Mask" user "Board Geometry/Soldermask Bottom")
		(17 "Dwgs.User" user "User.Drawings")
		(19 "Cmts.User" user "User.Comments")
		(21 "Eco1.User" user "User.Eco1")
		(23 "Eco2.User" user "User.Eco2")
		(25 "Edge.Cuts" user "Board Geometry/Outline")
		(27 "Margin" user)
		(31 "F.CrtYd" user "Package Geometry/Place Bound Top")
		(29 "B.CrtYd" user "Package Geometry/Place Bound Bottom")
		(35 "F.Fab" user "Ref Des/Assembly Top")
		(33 "B.Fab" user "Ref Des/Assembly Bottom")
	)
	(footprint ""
		(layer "F.Cu")
		(at 310.937148 -258.091686)
		(property "Reference" "J2"
			(at -3.683 -81.702148 0)
			(unlocked yes)
			(layer "F.SilkS")
			(effects
				(font
					(size 0.7874 0.5842)
					(thickness 0.1524)
				)
				(justify left)
			)
		)
		(property "Value" ""
			(at 0 0 0)
			(layer "F.Fab")
			(effects
				(font
					(size 1.27 1.27)
				)
			)
		)
		(duplicate_pad_numbers_are_jumpers no)
		(pad "183" smd rect
			(at 2.050034 -31.025084 270)
			(size 0.519938 1.4986)
			(layers "F.Cu" "F.Mask" "F.Paste")
			(net "M_A_CPU0_SA_DQ<23>")
		)
		(pad "184" smd rect
			(at 2.050034 -30.174946 270)
			(size 0.519938 1.4986)
			(layers "F.Cu" "F.Mask" "F.Paste")
			(net "GND")
		)
		(pad "185" smd rect
			(at 2.050034 -29.325062 270)
			(size 0.519938 1.4986)
			(layers "F.Cu" "F.Mask" "F.Paste")
			(net "M_A_CPU0_SA_DQ<26>")
		)
		(pad "186" smd rect
			(at 2.050034 -28.474924 270)
			(size 0.519938 1.4986)
			(layers "F.Cu" "F.Mask" "F.Paste")
			(net "GND")
		)
		(pad "187" smd rect
			(at 2.050034 -27.62504 270)
			(size 0.519938 1.4986)
			(layers "F.Cu" "F.Mask" "F.Paste")
			(net "M_A_CPU0_SA_DQ<27>")
		)
		(pad "188" smd rect
			(at 2.050034 -26.774902 270)
			(size 0.519938 1.4986)
			(layers "F.Cu" "F.Mask" "F.Paste")
			(net "GND")
		)
		(pad "189" smd rect
			(at 2.050034 -25.925018 270)
			(size 0.519938 1.4986)
			(layers "F.Cu" "F.Mask" "F.Paste")
			(net "M_A_CPU0_SA_DQS_DN<8>")
		)
		(pad "190" smd rect
			(at 2.050034 -25.07488 270)
			(size 0.519938 1.4986)
			(layers "F.Cu" "F.Mask" "F.Paste")
			(net "M_A_CPU0_SA_DQS_DP<8>")
		)
		(pad "191" smd rect
			(at 2.050034 -24.224996 270)
			(size 0.519938 1.4986)
			(layers "F.Cu" "F.Mask" "F.Paste")
			(net "GND")
		)
		(pad "192" smd rect
			(at 2.050034 -23.375112 270)
			(size 0.519938 1.4986)
			(layers "F.Cu" "F.Mask" "F.Paste")
			(net "M_A_CPU0_SA_DQ<30>")
		)
		(pad "193" smd rect
			(at 2.050034 -22.524974 270)
			(size 0.519938 1.4986)
			(layers "F.Cu" "F.Mask" "F.Paste")
			(net "GND")
		)
		(pad "194" smd rect
			(at 2.050034 -21.67509 270)
			(size 0.519938 1.4986)
			(layers "F.Cu" "F.Mask" "F.Paste")
			(net "M_A_CPU0_SA_DQ<31>")
		)
		(pad "195" smd rect
			(at 2.050034 -20.824952 270)
			(size 0.519938 1.4986)
			(layers "F.Cu" "F.Mask" "F.Paste")
			(net "GND")
		)
		(pad "196" smd rect
			(at 2.050034 -19.975068 270)
			(size 0.519938 1.4986)
			(layers "F.Cu" "F.Mask" "F.Paste")
			(net "M_A_CPU0_SA_CB<2>")
		)
		(pad "197" smd rect
			(at 2.050034 -19.12493 270)
			(size 0.519938 1.4986)
			(layers "F.Cu" "F.Mask" "F.Paste")
			(net "GND")
		)
		(pad "198" smd rect
			(at 2.050034 -18.275046 270)
			(size 0.519938 1.4986)
			(layers "F.Cu" "F.Mask" "F.Paste")
			(net "M_A_CPU0_SA_CB<3>")
		)
		(pad "199" smd rect
			(at 2.050034 -17.424908 270)
			(size 0.519938 1.4986)
			(layers "F.Cu" "F.Mask" "F.Paste")
			(net "GND")
		)
		(pad "200" smd rect
			(at 2.050034 -16.575024 270)
			(size 0.519938 1.4986)
			(layers "F.Cu" "F.Mask" "F.Paste")
			(net "M_A_CPU0_SA_DQS_DN<9>")
		)
		(pad "201" smd rect
			(at 2.050034 -15.724886 270)
			(size 0.519938 1.4986)
			(layers "F.Cu" "F.Mask" "F.Paste")
			(net "M_A_CPU0_SA_DQS_DP<9>")
		)
		(pad "202" smd rect
			(at 2.050034 -14.875002 270)
			(size 0.519938 1.4986)
			(layers "F.Cu" "F.Mask" "F.Paste")
			(net "GND")
		)
		(pad "203" smd rect
			(at 2.050034 -14.025118 270)
			(size 0.519938 1.4986)
			(layers "F.Cu" "F.Mask" "F.Paste")
			(net "M_A_CPU0_SA_CB<6>")
		)
		(pad "204" smd rect
			(at 2.050034 -13.17498 270)
			(size 0.519938 1.4986)
			(layers "F.Cu" "F.Mask" "F.Paste")
			(net "GND")
		)
		(pad "205" smd rect
			(at 2.050034 -12.325096 270)
			(size 0.519938 1.4986)
			(layers "F.Cu" "F.Mask" "F.Paste")
			(net "M_A_CPU0_SA_CB<7>")
		)
		(pad "206" smd rect
			(at 2.050034 -11.474958 270)
			(size 0.519938 1.4986)
			(layers "F.Cu" "F.Mask" "F.Paste")
			(net "GND")
		)
		(pad "207" smd rect
			(at 2.050034 -10.625074 270)
			(size 0.519938 1.4986)
			(layers "F.Cu" "F.Mask" "F.Paste")
			(net "RST_M_AB_CPU0_FPGA_N")
		)
		(pad "208" smd rect
			(at 2.050034 -9.774936 270)
			(size 0.519938 1.4986)
			(layers "F.Cu" "F.Mask" "F.Paste")
			(net "GND")
		)
		(pad "209" smd rect
			(at 2.050034 -8.925052 270)
			(size 0.519938 1.4986)
			(layers "F.Cu" "F.Mask" "F.Paste")
			(net "M_A_CPU0_SA_CS_N<3>")
		)
		(pad "210" smd rect
			(at 2.050034 -8.074914 270)
			(size 0.519938 1.4986)
			(layers "F.Cu" "F.Mask" "F.Paste")
			(net "GND")
		)
		(pad "211" smd rect
			(at 2.050034 -7.22503 270)
			(size 0.519938 1.4986)
			(layers "F.Cu" "F.Mask" "F.Paste")
			(net "M_A_CPU0_SA_CA<1>")
		)
		(pad "212" smd rect
			(at 2.050034 -6.374892 270)
			(size 0.519938 1.4986)
			(layers "F.Cu" "F.Mask" "F.Paste")
			(net "GND")
		)
		(pad "213" smd rect
			(at 2.050034 -5.525008 270)
			(size 0.519938 1.4986)
			(layers "F.Cu" "F.Mask" "F.Paste")
			(net "M_A_CPU0_SA_CA<3>")
		)
		(pad "214" smd rect
			(at 2.050034 -4.675124 270)
			(size 0.519938 1.4986)
			(layers "F.Cu" "F.Mask" "F.Paste")
			(net "GND")
		)
		(pad "215" smd rect
			(at 2.050034 -3.824986 270)
			(size 0.519938 1.4986)
			(layers "F.Cu" "F.Mask" "F.Paste")
			(net "M_A_CPU0_SA_CA<5>")
		)
		(pad "216" smd rect
			(at 2.050034 -2.975102 270)
			(size 0.519938 1.4986)
			(layers "F.Cu" "F.Mask" "F.Paste")
			(net "GND")
		)
		(pad "217" smd rect
			(at 2.050034 -2.124964 270)
			(size 0.519938 1.4986)
			(layers "F.Cu" "F.Mask" "F.Paste")
			(net "M_A_CPU0_CLK_DP<1>")
		)
		(pad "218" smd rect
			(at 2.050034 -1.27508 270)
			(size 0.519938 1.4986)
			(layers "F.Cu" "F.Mask" "F.Paste")
			(net "M_A_CPU0_CLK_DN<1>")
		)
		(pad "219" smd rect
			(at 2.050034 -0.424942 270)
			(size 0.519938 1.4986)
			(layers "F.Cu" "F.Mask" "F.Paste")
			(net "GND")
		)
		(pad "220" smd rect
			(at 2.050034 5.525008 270)
			(size 0.519938 1.4986)
			(layers "F.Cu" "F.Mask" "F.Paste")
			(net "TP_CHA_CPU0_DIMM2_FRU_4")
		)
		(pad "221" smd rect
			(at 2.050034 6.374892 270)
			(size 0.519938 1.4986)
			(layers "F.Cu" "F.Mask" "F.Paste")
			(net "M_A_CPU0_SB_CA<1>")
		)
		(pad "222" smd rect
			(at 2.050034 7.22503 270)
			(size 0.519938 1.4986)
			(layers "F.Cu" "F.Mask" "F.Paste")
			(net "GND")
		)
		(pad "223" smd rect
			(at 2.050034 8.074914 270)
			(size 0.519938 1.4986)
			(layers "F.Cu" "F.Mask" "F.Paste")
			(net "M_A_CPU0_SB_CA<3>")
		)
		(pad "224" smd rect
			(at 2.050034 8.925052 270)
			(size 0.519938 1.4986)
			(layers "F.Cu" "F.Mask" "F.Paste")
			(net "GND")
		)
		(pad "225" smd rect
			(at 2.050034 9.774936 270)
			(size 0.519938 1.4986)
			(layers "F.Cu" "F.Mask" "F.Paste")
			(net "M_A_CPU0_SB_CA<5>")
		)
		(pad "226" smd rect
			(at 2.050034 10.625074 270)
			(size 0.519938 1.4986)
			(layers "F.Cu" "F.Mask" "F.Paste")
			(net "GND")
		)
		(pad "227" smd rect
			(at 2.050034 11.474958 270)
			(size 0.519938 1.4986)
			(layers "F.Cu" "F.Mask" "F.Paste")
			(net "M_A_CPU0_SB_PAR")
		)
		(pad "228" smd rect
			(at 2.050034 12.325096 270)
			(size 0.519938 1.4986)
			(layers "F.Cu" "F.Mask" "F.Paste")
			(net "GND")
		)
	)
)
